# SCM (Grand Teton) — schematic netlist excerpt (pin names and nets, part order shuffled) for the footprints in the layout excerpt that follows; sources: Cadence DE-HDL packaged netlist, KiCad conversion of 12092022_DA0F0TMDCD0_F0T_Management_Board_D_brd_V3_OCP.brd

PC271  Q_CAP  0.1UF 25V 10% X7R  pkg 0402  page 51 : A = P5V_AUX_REF ; B = GND
R867  Q_RES  1K 1% EMPTY  pkg 0402LF  page 21 : A = P3V3_AUX ; B = EMMC_WP

(kicad_pcb
	(version 20260206)
	(generator "pcbnew")
	(generator_version "10.0")
	(general
		(thickness 1.6)
		(legacy_teardrops no)
	)
	(paper "A4")
	(title_block
		(title "12092022_DA0F0TMDCD0_F0T_Management_Board_D_brd_V3_OCP.brd")
		(comment 1 "Grand Teton / footprints 176-177 of 1440")
	)
	(layers
		(0 "F.Cu" signal "TOP")
		(4 "In1.Cu" signal "GND")
		(6 "In2.Cu" signal "IN1")
		(8 "In3.Cu" signal "GND1")
		(10 "In4.Cu" signal "IN2")
		(12 "In5.Cu" signal "VCC")
		(14 "In6.Cu" signal "VCC1")
		(16 "In7.Cu" signal "IN3")
		(18 "In8.Cu" signal "GND2")
		(20 "In9.Cu" signal "IN4")
		(22 "In10.Cu" signal "GND3")
		(2 "B.Cu" signal "BOTTOM")
		(9 "F.Adhes" user "F.Adhesive")
		(11 "B.Adhes" user "B.Adhesive")
		(13 "F.Paste" user "Package Geometry/Pastemask Top")
		(15 "B.Paste" user "Package Geometry/Pastemask Bottom")
		(5 "F.SilkS" user "Ref Des/Silkscreen Top")
		(7 "B.SilkS" user "Ref Des/Silkscreen Bottom")
		(1 "F.Mask" user "Board Geometry/Soldermask Top")
		(3 "B.Mask" user "Board Geometry/Soldermask Bottom")
		(17 "Dwgs.User" user "User.Drawings")
		(19 "Cmts.User" user "User.Comments")
		(21 "Eco1.User" user "User.Eco1")
		(23 "Eco2.User" user "User.Eco2")
		(25 "Edge.Cuts" user "Board Geometry/Outline")
		(27 "Margin" user)
		(31 "F.CrtYd" user "Package Geometry/Place Bound Top")
		(29 "B.CrtYd" user "Package Geometry/Place Bound Bottom")
		(35 "F.Fab" user "Ref Des/Assembly Top")
		(33 "B.Fab" user "Ref Des/Assembly Bottom")
	)
	(footprint ""
		(layer "F.Cu")
		(at 11.147044 -48.64989)
		(property "Reference" "PC271"
			(at 0 0 0)
			(layer "F.SilkS")
			(hide yes)
			(effects
				(font
					(size 1.27 1.27)
				)
			)
		)
		(property "Value" ""
			(at 0 0 0)
			(layer "F.Fab")
			(effects
				(font
					(size 1.27 1.27)
				)
			)
		)
		(duplicate_pad_numbers_are_jumpers no)
		(fp_line
			(start -0.7874 -0.4064)
			(end 0.7874 -0.4064)
			(stroke
				(width 0.1524)
				(type default)
			)
			(layer "F.SilkS")
		)
		(fp_line
			(start -0.7874 0.4064)
			(end -0.7874 -0.4064)
			(stroke
				(width 0.1524)
				(type default)
			)
			(layer "F.SilkS")
		)
		(fp_line
			(start 0.7874 -0.4064)
			(end 0.7874 0.4064)
			(stroke
				(width 0.1524)
				(type default)
			)
			(layer "F.SilkS")
		)
		(fp_line
			(start 0.7874 0.4064)
			(end -0.7874 0.4064)
			(stroke
				(width 0.1524)
				(type default)
			)
			(layer "F.SilkS")
		)
		(fp_line
			(start -0.67945 -0.305054)
			(end -0.12065 -0.305054)
			(stroke
				(width 0.1)
				(type default)
			)
			(layer "F.Fab")
		)
		(fp_line
			(start -0.67945 0.3048)
			(end -0.67945 -0.305054)
			(stroke
				(width 0.1)
				(type default)
			)
			(layer "F.Fab")
		)
		(fp_line
			(start -0.12065 -0.305054)
			(end -0.12065 -0.2794)
			(stroke
				(width 0.1)
				(type default)
			)
			(layer "F.Fab")
		)
		(fp_line
			(start -0.12065 -0.2794)
			(end 0.12065 -0.2794)
			(stroke
				(width 0.1)
				(type default)
			)
			(layer "F.Fab")
		)
		(fp_line
			(start -0.12065 0.2794)
			(end -0.12065 0.3048)
			(stroke
				(width 0.1)
				(type default)
			)
			(layer "F.Fab")
		)
		(fp_line
			(start -0.12065 0.3048)
			(end -0.67945 0.3048)
			(stroke
				(width 0.1)
				(type default)
			)
			(layer "F.Fab")
		)
		(fp_line
			(start 0.120396 0.2794)
			(end -0.12065 0.2794)
			(stroke
				(width 0.1)
				(type default)
			)
			(layer "F.Fab")
		)
		(fp_line
			(start 0.120396 0.3048)
			(end 0.120396 0.2794)
			(stroke
				(width 0.1)
				(type default)
			)
			(layer "F.Fab")
		)
		(fp_line
			(start 0.12065 -0.3048)
			(end 0.67945 -0.3048)
			(stroke
				(width 0.1)
				(type default)
			)
			(layer "F.Fab")
		)
		(fp_line
			(start 0.12065 -0.2794)
			(end 0.12065 -0.3048)
			(stroke
				(width 0.1)
				(type default)
			)
			(layer "F.Fab")
		)
		(fp_line
			(start 0.67945 -0.3048)
			(end 0.67945 0.3048)
			(stroke
				(width 0.1)
				(type default)
			)
			(layer "F.Fab")
		)
		(fp_line
			(start 0.67945 0.3048)
			(end 0.120396 0.3048)
			(stroke
				(width 0.1)
				(type default)
			)
			(layer "F.Fab")
		)
		(pad "1" smd circle
			(at -0.40005 0)
			(size 0 0)
			(layers "F.Cu" "F.Mask" "F.Paste")
			(net "P5V_AUX_REF")
		)
		(pad "2" smd circle
			(at 0.40005 0)
			(size 0 0)
			(layers "F.Cu" "F.Mask" "F.Paste")
			(net "GND")
		)
	)
	(footprint ""
		(layer "F.Cu")
		(at 28.2194 -70.5358 90)
		(property "Reference" "R867"
			(at 0 0 90)
			(layer "F.SilkS")
			(hide yes)
			(effects
				(font
					(size 1.27 1.27)
				)
			)
		)
		(property "Value" ""
			(at 0 0 90)
			(layer "F.Fab")
			(effects
				(font
					(size 1.27 1.27)
				)
			)
		)
		(duplicate_pad_numbers_are_jumpers no)
		(fp_line
			(start 0.7874 -0.4064)
			(end 0.7874 0.4064)
			(stroke
				(width 0.1524)
				(type default)
			)
			(layer "F.SilkS")
		)
		(fp_line
			(start -0.7874 -0.4064)
			(end 0.7874 -0.4064)
			(stroke
				(width 0.1524)
				(type default)
			)
			(layer "F.SilkS")
		)
		(fp_line
			(start 0.7874 0.4064)
			(end -0.7874 0.4064)
			(stroke
				(width 0.1524)
				(type default)
			)
			(layer "F.SilkS")
		)
		(fp_line
			(start -0.7874 0.4064)
			(end -0.7874 -0.4064)
			(stroke
				(width 0.1524)
				(type default)
			)
			(layer "F.SilkS")
		)
		(fp_line
			(start -0.12065 -0.305054)
			(end -0.12065 -0.2794)
			(stroke
				(width 0.1)
				(type default)
			)
			(layer "F.Fab")
		)
		(fp_line
			(start -0.67945 -0.305054)
			(end -0.12065 -0.305054)
			(stroke
				(width 0.1)
				(type default)
			)
			(layer "F.Fab")
		)
		(fp_line
			(start 0.67945 -0.3048)
			(end 0.67945 0.3048)
			(stroke
				(width 0.1)
				(type default)
			)
			(layer "F.Fab")
		)
		(fp_line
			(start 0.12065 -0.3048)
			(end 0.67945 -0.3048)
			(stroke
				(width 0.1)
				(type default)
			)
			(layer "F.Fab")
		)
		(fp_line
			(start 0.12065 -0.2794)
			(end 0.12065 -0.3048)
			(stroke
				(width 0.1)
				(type default)
			)
			(layer "F.Fab")
		)
		(fp_line
			(start -0.12065 -0.2794)
			(end 0.12065 -0.2794)
			(stroke
				(width 0.1)
				(type default)
			)
			(layer "F.Fab")
		)
		(fp_line
			(start 0.120396 0.2794)
			(end -0.12065 0.2794)
			(stroke
				(width 0.1)
				(type default)
			)
			(layer "F.Fab")
		)
		(fp_line
			(start -0.12065 0.2794)
			(end -0.12065 0.3048)
			(stroke
				(width 0.1)
				(type default)
			)
			(layer "F.Fab")
		)
		(fp_line
			(start 0.67945 0.3048)
			(end 0.120396 0.3048)
			(stroke
				(width 0.1)
				(type default)
			)
			(layer "F.Fab")
		)
		(fp_line
			(start 0.120396 0.3048)
			(end 0.120396 0.2794)
			(stroke
				(width 0.1)
				(type default)
			)
			(layer "F.Fab")
		)
		(fp_line
			(start -0.12065 0.3048)
			(end -0.67945 0.3048)
			(stroke
				(width 0.1)
				(type default)
			)
			(layer "F.Fab")
		)
		(fp_line
			(start -0.67945 0.3048)
			(end -0.67945 -0.305054)
			(stroke
				(width 0.1)
				(type default)
			)
			(layer "F.Fab")
		)
		(pad "1" smd circle
			(at -0.40005 0 90)
			(size 0 0)
			(layers "F.Cu" "F.Mask" "F.Paste")
			(net "P3V3_AUX")
		)
		(pad "2" smd circle
			(at 0.40005 0 90)
			(size 0 0)
			(layers "F.Cu" "F.Mask" "F.Paste")
			(net "EMMC_WP")
		)
	)
)
